(kicad_pcb
	(version 20260206)
	(generator "pcbnew")
	(generator_version "10.0")
	(general
		(thickness 1.6)
		(legacy_teardrops no)
	)
	(paper "A4")
	(title_block
		(title "03242023_DA0F0TMBIJ0_F0T_Motherboard_J_brd_V01_OCP.brd")
		(comment 1 "Grand Teton / footprints 653-659 of 6105")
	)
	(layers
		(0 "F.Cu" signal "TOP")
		(4 "In1.Cu" signal "GND")
		(6 "In2.Cu" signal "IN1")
		(8 "In3.Cu" signal "GND1")
		(10 "In4.Cu" signal "IN2")
		(12 "In5.Cu" signal "GND2")
		(14 "In6.Cu" signal "IN3")
		(16 "In7.Cu" signal "GND3")
		(18 "In8.Cu" signal "VCC")
		(20 "In9.Cu" signal "VCC1")
		(22 "In10.Cu" signal "GND4")
		(24 "In11.Cu" signal "IN4")
		(26 "In12.Cu" signal "GND5")
		(28 "In13.Cu" signal "IN5")
		(30 "In14.Cu" signal "GND6")
		(32 "In15.Cu" signal "IN6")
		(34 "In16.Cu" signal "GND7")
		(2 "B.Cu" signal "BOTTOM")
		(9 "F.Adhes" user "F.Adhesive")
		(11 "B.Adhes" user "B.Adhesive")
		(13 "F.Paste" user "Package Geometry/Pastemask Top")
		(15 "B.Paste" user "Package Geometry/Pastemask Bottom")
		(5 "F.SilkS" user "Ref Des/Silkscreen Top")
		(7 "B.SilkS" user "Ref Des/Silkscreen Bottom")
		(1 "F.Mask" user "Board Geometry/Soldermask Top")
		(3 "B.Mask" user "Board Geometry/Soldermask Bottom")
		(17 "Dwgs.User" user "User.Drawings")
		(19 "Cmts.User" user "User.Comments")
		(21 "Eco1.User" user "User.Eco1")
		(23 "Eco2.User" user "User.Eco2")
		(25 "Edge.Cuts" user "Board Geometry/Outline")
		(27 "Margin" user)
		(31 "F.CrtYd" user "Package Geometry/Place Bound Top")
		(29 "B.CrtYd" user "Package Geometry/Place Bound Bottom")
		(35 "F.Fab" user "Ref Des/Assembly Top")
		(33 "B.Fab" user "Ref Des/Assembly Bottom")
	)
	(footprint ""
		(layer "F.Cu")
		(at 428.283116 -109.26699 90)
		(property "Reference" "PR3791"
			(at 0 0 90)
			(layer "F.SilkS")
			(hide yes)
			(effects
				(font
					(size 1.27 1.27)
				)
			)
		)
		(property "Value" ""
			(at 0 0 90)
			(layer "F.Fab")
			(effects
				(font
					(size 1.27 1.27)
				)
			)
		)
		(duplicate_pad_numbers_are_jumpers no)
		(fp_line
			(start 0.7874 -0.4064)
			(end 0.7874 0.4064)
			(stroke
				(width 0.1524)
				(type default)
			)
			(layer "F.SilkS")
		)
		(fp_line
			(start -0.7874 -0.4064)
			(end 0.7874 -0.4064)
			(stroke
				(width 0.1524)
				(type default)
			)
			(layer "F.SilkS")
		)
		(fp_line
			(start 0.7874 0.4064)
			(end -0.7874 0.4064)
			(stroke
				(width 0.1524)
				(type default)
			)
			(layer "F.SilkS")
		)
		(fp_line
			(start -0.7874 0.4064)
			(end -0.7874 -0.4064)
			(stroke
				(width 0.1524)
				(type default)
			)
			(layer "F.SilkS")
		)
		(fp_line
			(start -0.12065 -0.305054)
			(end -0.12065 -0.2794)
			(stroke
				(width 0.1)
				(type default)
			)
			(layer "F.Fab")
		)
		(fp_line
			(start -0.67945 -0.305054)
			(end -0.12065 -0.305054)
			(stroke
				(width 0.1)
				(type default)
			)
			(layer "F.Fab")
		)
		(fp_line
			(start 0.67945 -0.3048)
			(end 0.67945 0.3048)
			(stroke
				(width 0.1)
				(type default)
			)
			(layer "F.Fab")
		)
		(fp_line
			(start 0.12065 -0.3048)
			(end 0.67945 -0.3048)
			(stroke
				(width 0.1)
				(type default)
			)
			(layer "F.Fab")
		)
		(fp_line
			(start 0.12065 -0.2794)
			(end 0.12065 -0.3048)
			(stroke
				(width 0.1)
				(type default)
			)
			(layer "F.Fab")
		)
		(fp_line
			(start -0.12065 -0.2794)
			(end 0.12065 -0.2794)
			(stroke
				(width 0.1)
				(type default)
			)
			(layer "F.Fab")
		)
		(fp_line
			(start 0.120396 0.2794)
			(end -0.12065 0.2794)
			(stroke
				(width 0.1)
				(type default)
			)
			(layer "F.Fab")
		)
		(fp_line
			(start -0.12065 0.2794)
			(end -0.12065 0.3048)
			(stroke
				(width 0.1)
				(type default)
			)
			(layer "F.Fab")
		)
		(fp_line
			(start 0.67945 0.3048)
			(end 0.120396 0.3048)
			(stroke
				(width 0.1)
				(type default)
			)
			(layer "F.Fab")
		)
		(fp_line
			(start 0.120396 0.3048)
			(end 0.120396 0.2794)
			(stroke
				(width 0.1)
				(type default)
			)
			(layer "F.Fab")
		)
		(fp_line
			(start -0.12065 0.3048)
			(end -0.67945 0.3048)
			(stroke
				(width 0.1)
				(type default)
			)
			(layer "F.Fab")
		)
		(fp_line
			(start -0.67945 0.3048)
			(end -0.67945 -0.305054)
			(stroke
				(width 0.1)
				(type default)
			)
			(layer "F.Fab")
		)
		(pad "1" smd circle
			(at -0.40005 0 90)
			(size 0 0)
			(layers "F.Cu" "F.Mask" "F.Paste")
			(net "P3V3_OCP_OV_1")
		)
		(pad "2" smd circle
			(at 0.40005 0 90)
			(size 0 0)
			(layers "F.Cu" "F.Mask" "F.Paste")
			(net "GND")
		)
	)
	(footprint ""
		(layer "F.Cu")
		(at 160.866074 -402.371052 -90)
		(property "Reference" "C768"
			(at 0 0 270)
			(layer "F.SilkS")
			(hide yes)
			(effects
				(font
					(size 1.27 1.27)
				)
			)
		)
		(property "Value" ""
			(at 0 0 270)
			(layer "F.Fab")
			(effects
				(font
					(size 1.27 1.27)
				)
			)
		)
		(duplicate_pad_numbers_are_jumpers no)
		(fp_line
			(start -0.299974 0.150114)
			(end -0.299974 -0.150114)
			(stroke
				(width 0.1)
				(type default)
			)
			(layer "F.Fab")
		)
		(fp_line
			(start 0.299974 0.150114)
			(end -0.299974 0.150114)
			(stroke
				(width 0.1)
				(type default)
			)
			(layer "F.Fab")
		)
		(fp_line
			(start -0.299974 -0.150114)
			(end 0.299974 -0.150114)
			(stroke
				(width 0.1)
				(type default)
			)
			(layer "F.Fab")
		)
		(fp_line
			(start 0.299974 -0.150114)
			(end 0.299974 0.150114)
			(stroke
				(width 0.1)
				(type default)
			)
			(layer "F.Fab")
		)
		(pad "1" smd rect
			(at -0.2667 0 270)
			(size 0.3048 0.381)
			(layers "F.Cu" "F.Mask" "F.Paste")
			(net "P5E_CPU1_PE2_TX_C_DN<2>")
		)
		(pad "2" smd rect
			(at 0.2667 0 270)
			(size 0.3048 0.381)
			(layers "F.Cu" "F.Mask" "F.Paste")
			(net "P5E_CPU1_PE2_TX_DN<2>")
		)
	)
	(footprint ""
		(layer "F.Cu")
		(at 142.918434 -408.517344 -90)
		(property "Reference" "C1530"
			(at 0 0 270)
			(layer "F.SilkS")
			(hide yes)
			(effects
				(font
					(size 1.27 1.27)
				)
			)
		)
		(property "Value" ""
			(at 0 0 270)
			(layer "F.Fab")
			(effects
				(font
					(size 1.27 1.27)
				)
			)
		)
		(duplicate_pad_numbers_are_jumpers no)
		(fp_line
			(start -0.299974 0.150114)
			(end -0.299974 -0.150114)
			(stroke
				(width 0.1)
				(type default)
			)
			(layer "F.Fab")
		)
		(fp_line
			(start 0.299974 0.150114)
			(end -0.299974 0.150114)
			(stroke
				(width 0.1)
				(type default)
			)
			(layer "F.Fab")
		)
		(fp_line
			(start -0.299974 -0.150114)
			(end 0.299974 -0.150114)
			(stroke
				(width 0.1)
				(type default)
			)
			(layer "F.Fab")
		)
		(fp_line
			(start 0.299974 -0.150114)
			(end 0.299974 0.150114)
			(stroke
				(width 0.1)
				(type default)
			)
			(layer "F.Fab")
		)
		(pad "1" smd rect
			(at -0.2667 0 270)
			(size 0.3048 0.381)
			(layers "F.Cu" "F.Mask" "F.Paste")
			(net "P5E_CPU1_PE3_TX_C_DN<8>")
		)
		(pad "2" smd rect
			(at 0.2667 0 270)
			(size 0.3048 0.381)
			(layers "F.Cu" "F.Mask" "F.Paste")
			(net "P5E_CPU1_PE3_TX_DN<8>")
		)
	)
	(footprint ""
		(layer "F.Cu")
		(at 204.93736 -120.614948)
		(property "Reference" "R4174"
			(at 0 0 0)
			(layer "F.SilkS")
			(hide yes)
			(effects
				(font
					(size 1.27 1.27)
				)
			)
		)
		(property "Value" ""
			(at 0 0 0)
			(layer "F.Fab")
			(effects
				(font
					(size 1.27 1.27)
				)
			)
		)
		(duplicate_pad_numbers_are_jumpers no)
		(fp_line
			(start -0.7874 -0.4064)
			(end 0.7874 -0.4064)
			(stroke
				(width 0.1524)
				(type default)
			)
			(layer "F.SilkS")
		)
		(fp_line
			(start -0.7874 0.4064)
			(end -0.7874 -0.4064)
			(stroke
				(width 0.1524)
				(type default)
			)
			(layer "F.SilkS")
		)
		(fp_line
			(start 0.7874 -0.4064)
			(end 0.7874 0.4064)
			(stroke
				(width 0.1524)
				(type default)
			)
			(layer "F.SilkS")
		)
		(fp_line
			(start 0.7874 0.4064)
			(end -0.7874 0.4064)
			(stroke
				(width 0.1524)
				(type default)
			)
			(layer "F.SilkS")
		)
		(fp_line
			(start -0.67945 -0.305054)
			(end -0.12065 -0.305054)
			(stroke
				(width 0.1)
				(type default)
			)
			(layer "F.Fab")
		)
		(fp_line
			(start -0.67945 0.3048)
			(end -0.67945 -0.305054)
			(stroke
				(width 0.1)
				(type default)
			)
			(layer "F.Fab")
		)
		(fp_line
			(start -0.12065 -0.305054)
			(end -0.12065 -0.2794)
			(stroke
				(width 0.1)
				(type default)
			)
			(layer "F.Fab")
		)
		(fp_line
			(start -0.12065 -0.2794)
			(end 0.12065 -0.2794)
			(stroke
				(width 0.1)
				(type default)
			)
			(layer "F.Fab")
		)
		(fp_line
			(start -0.12065 0.2794)
			(end -0.12065 0.3048)
			(stroke
				(width 0.1)
				(type default)
			)
			(layer "F.Fab")
		)
		(fp_line
			(start -0.12065 0.3048)
			(end -0.67945 0.3048)
			(stroke
				(width 0.1)
				(type default)
			)
			(layer "F.Fab")
		)
		(fp_line
			(start 0.120396 0.2794)
			(end -0.12065 0.2794)
			(stroke
				(width 0.1)
				(type default)
			)
			(layer "F.Fab")
		)
		(fp_line
			(start 0.120396 0.3048)
			(end 0.120396 0.2794)
			(stroke
				(width 0.1)
				(type default)
			)
			(layer "F.Fab")
		)
		(fp_line
			(start 0.12065 -0.3048)
			(end 0.67945 -0.3048)
			(stroke
				(width 0.1)
				(type default)
			)
			(layer "F.Fab")
		)
		(fp_line
			(start 0.12065 -0.2794)
			(end 0.12065 -0.3048)
			(stroke
				(width 0.1)
				(type default)
			)
			(layer "F.Fab")
		)
		(fp_line
			(start 0.67945 -0.3048)
			(end 0.67945 0.3048)
			(stroke
				(width 0.1)
				(type default)
			)
			(layer "F.Fab")
		)
		(fp_line
			(start 0.67945 0.3048)
			(end 0.120396 0.3048)
			(stroke
				(width 0.1)
				(type default)
			)
			(layer "F.Fab")
		)
		(pad "1" smd circle
			(at -0.40005 0)
			(size 0 0)
			(layers "F.Cu" "F.Mask" "F.Paste")
			(net "RST_PCIE_PCH_DEV_PERST_N")
		)
		(pad "2" smd circle
			(at 0.40005 0)
			(size 0 0)
			(layers "F.Cu" "F.Mask" "F.Paste")
			(net "RST_PCIE_PCH_DEV_PERST_E1S_R_N")
		)
	)
	(footprint ""
		(layer "F.Cu")
		(at 66.150744 -14.26464 180)
		(property "Reference" "PC2152"
			(at 0 0 180)
			(layer "F.SilkS")
			(hide yes)
			(effects
				(font
					(size 1.27 1.27)
				)
			)
		)
		(property "Value" ""
			(at 0 0 180)
			(layer "F.Fab")
			(effects
				(font
					(size 1.27 1.27)
				)
			)
		)
		(duplicate_pad_numbers_are_jumpers no)
		(fp_line
			(start 0.7874 0.4064)
			(end -0.7874 0.4064)
			(stroke
				(width 0.1524)
				(type default)
			)
			(layer "F.SilkS")
		)
		(fp_line
			(start 0.7874 -0.4064)
			(end 0.7874 0.4064)
			(stroke
				(width 0.1524)
				(type default)
			)
			(layer "F.SilkS")
		)
		(fp_line
			(start -0.7874 0.4064)
			(end -0.7874 -0.4064)
			(stroke
				(width 0.1524)
				(type default)
			)
			(layer "F.SilkS")
		)
		(fp_line
			(start -0.7874 -0.4064)
			(end 0.7874 -0.4064)
			(stroke
				(width 0.1524)
				(type default)
			)
			(layer "F.SilkS")
		)
		(fp_line
			(start 0.67945 0.3048)
			(end 0.120396 0.3048)
			(stroke
				(width 0.1)
				(type default)
			)
			(layer "F.Fab")
		)
		(fp_line
			(start 0.67945 -0.3048)
			(end 0.67945 0.3048)
			(stroke
				(width 0.1)
				(type default)
			)
			(layer "F.Fab")
		)
		(fp_line
			(start 0.12065 -0.2794)
			(end 0.12065 -0.3048)
			(stroke
				(width 0.1)
				(type default)
			)
			(layer "F.Fab")
		)
		(fp_line
			(start 0.12065 -0.3048)
			(end 0.67945 -0.3048)
			(stroke
				(width 0.1)
				(type default)
			)
			(layer "F.Fab")
		)
		(fp_line
			(start 0.120396 0.3048)
			(end 0.120396 0.2794)
			(stroke
				(width 0.1)
				(type default)
			)
			(layer "F.Fab")
		)
		(fp_line
			(start 0.120396 0.2794)
			(end -0.12065 0.2794)
			(stroke
				(width 0.1)
				(type default)
			)
			(layer "F.Fab")
		)
		(fp_line
			(start -0.12065 0.3048)
			(end -0.67945 0.3048)
			(stroke
				(width 0.1)
				(type default)
			)
			(layer "F.Fab")
		)
		(fp_line
			(start -0.12065 0.2794)
			(end -0.12065 0.3048)
			(stroke
				(width 0.1)
				(type default)
			)
			(layer "F.Fab")
		)
		(fp_line
			(start -0.12065 -0.2794)
			(end 0.12065 -0.2794)
			(stroke
				(width 0.1)
				(type default)
			)
			(layer "F.Fab")
		)
		(fp_line
			(start -0.12065 -0.305054)
			(end -0.12065 -0.2794)
			(stroke
				(width 0.1)
				(type default)
			)
			(layer "F.Fab")
		)
		(fp_line
			(start -0.67945 0.3048)
			(end -0.67945 -0.305054)
			(stroke
				(width 0.1)
				(type default)
			)
			(layer "F.Fab")
		)
		(fp_line
			(start -0.67945 -0.305054)
			(end -0.12065 -0.305054)
			(stroke
				(width 0.1)
				(type default)
			)
			(layer "F.Fab")
		)
		(pad "1" smd circle
			(at -0.40005 0 180)
			(size 0 0)
			(layers "F.Cu" "F.Mask" "F.Paste")
			(net "P12V_OCP_V3_2")
		)
		(pad "2" smd circle
			(at 0.40005 0 180)
			(size 0 0)
			(layers "F.Cu" "F.Mask" "F.Paste")
			(net "GND")
		)
	)
	(footprint ""
		(layer "F.Cu")
		(at 428.62373 -120.365012 180)
		(property "Reference" "PC629"
			(at 0 0 180)
			(layer "F.SilkS")
			(hide yes)
			(effects
				(font
					(size 1.27 1.27)
				)
			)
		)
		(property "Value" ""
			(at 0 0 180)
			(layer "F.Fab")
			(effects
				(font
					(size 1.27 1.27)
				)
			)
		)
		(duplicate_pad_numbers_are_jumpers no)
		(fp_line
			(start 0.7874 0.4064)
			(end -0.7874 0.4064)
			(stroke
				(width 0.1524)
				(type default)
			)
			(layer "F.SilkS")
		)
		(fp_line
			(start 0.7874 -0.4064)
			(end 0.7874 0.4064)
			(stroke
				(width 0.1524)
				(type default)
			)
			(layer "F.SilkS")
		)
		(fp_line
			(start -0.7874 0.4064)
			(end -0.7874 -0.4064)
			(stroke
				(width 0.1524)
				(type default)
			)
			(layer "F.SilkS")
		)
		(fp_line
			(start -0.7874 -0.4064)
			(end 0.7874 -0.4064)
			(stroke
				(width 0.1524)
				(type default)
			)
			(layer "F.SilkS")
		)
		(fp_line
			(start 0.67945 0.3048)
			(end 0.120396 0.3048)
			(stroke
				(width 0.1)
				(type default)
			)
			(layer "F.Fab")
		)
		(fp_line
			(start 0.67945 -0.3048)
			(end 0.67945 0.3048)
			(stroke
				(width 0.1)
				(type default)
			)
			(layer "F.Fab")
		)
		(fp_line
			(start 0.12065 -0.2794)
			(end 0.12065 -0.3048)
			(stroke
				(width 0.1)
				(type default)
			)
			(layer "F.Fab")
		)
		(fp_line
			(start 0.12065 -0.3048)
			(end 0.67945 -0.3048)
			(stroke
				(width 0.1)
				(type default)
			)
			(layer "F.Fab")
		)
		(fp_line
			(start 0.120396 0.3048)
			(end 0.120396 0.2794)
			(stroke
				(width 0.1)
				(type default)
			)
			(layer "F.Fab")
		)
		(fp_line
			(start 0.120396 0.2794)
			(end -0.12065 0.2794)
			(stroke
				(width 0.1)
				(type default)
			)
			(layer "F.Fab")
		)
		(fp_line
			(start -0.12065 0.3048)
			(end -0.67945 0.3048)
			(stroke
				(width 0.1)
				(type default)
			)
			(layer "F.Fab")
		)
		(fp_line
			(start -0.12065 0.2794)
			(end -0.12065 0.3048)
			(stroke
				(width 0.1)
				(type default)
			)
			(layer "F.Fab")
		)
		(fp_line
			(start -0.12065 -0.2794)
			(end 0.12065 -0.2794)
			(stroke
				(width 0.1)
				(type default)
			)
			(layer "F.Fab")
		)
		(fp_line
			(start -0.12065 -0.305054)
			(end -0.12065 -0.2794)
			(stroke
				(width 0.1)
				(type default)
			)
			(layer "F.Fab")
		)
		(fp_line
			(start -0.67945 0.3048)
			(end -0.67945 -0.305054)
			(stroke
				(width 0.1)
				(type default)
			)
			(layer "F.Fab")
		)
		(fp_line
			(start -0.67945 -0.305054)
			(end -0.12065 -0.305054)
			(stroke
				(width 0.1)
				(type default)
			)
			(layer "F.Fab")
		)
		(pad "1" smd circle
			(at -0.40005 0 180)
			(size 0 0)
			(layers "F.Cu" "F.Mask" "F.Paste")
			(net "PVCCD_HV_CPU0_VCC")
		)
		(pad "2" smd circle
			(at 0.40005 0 180)
			(size 0 0)
			(layers "F.Cu" "F.Mask" "F.Paste")
			(net "GND")
		)
	)
	(footprint ""
		(layer "F.Cu")
		(at 101.833934 -392.63574 180)
		(property "Reference" "R3462"
			(at 0 0 180)
			(layer "F.SilkS")
			(hide yes)
			(effects
				(font
					(size 1.27 1.27)
				)
			)
		)
		(property "Value" ""
			(at 0 0 180)
			(layer "F.Fab")
			(effects
				(font
					(size 1.27 1.27)
				)
			)
		)
		(duplicate_pad_numbers_are_jumpers no)
		(fp_line
			(start 0.7874 0.4064)
			(end -0.7874 0.4064)
			(stroke
				(width 0.1524)
				(type default)
			)
			(layer "F.SilkS")
		)
		(fp_line
			(start 0.7874 -0.4064)
			(end 0.7874 0.4064)
			(stroke
				(width 0.1524)
				(type default)
			)
			(layer "F.SilkS")
		)
		(fp_line
			(start -0.7874 0.4064)
			(end -0.7874 -0.4064)
			(stroke
				(width 0.1524)
				(type default)
			)
			(layer "F.SilkS")
		)
		(fp_line
			(start -0.7874 -0.4064)
			(end 0.7874 -0.4064)
			(stroke
				(width 0.1524)
				(type default)
			)
			(layer "F.SilkS")
		)
		(fp_line
			(start 0.67945 0.3048)
			(end 0.120396 0.3048)
			(stroke
				(width 0.1)
				(type default)
			)
			(layer "F.Fab")
		)
		(fp_line
			(start 0.67945 -0.3048)
			(end 0.67945 0.3048)
			(stroke
				(width 0.1)
				(type default)
			)
			(layer "F.Fab")
		)
		(fp_line
			(start 0.12065 -0.2794)
			(end 0.12065 -0.3048)
			(stroke
				(width 0.1)
				(type default)
			)
			(layer "F.Fab")
		)
		(fp_line
			(start 0.12065 -0.3048)
			(end 0.67945 -0.3048)
			(stroke
				(width 0.1)
				(type default)
			)
			(layer "F.Fab")
		)
		(fp_line
			(start 0.120396 0.3048)
			(end 0.120396 0.2794)
			(stroke
				(width 0.1)
				(type default)
			)
			(layer "F.Fab")
		)
		(fp_line
			(start 0.120396 0.2794)
			(end -0.12065 0.2794)
			(stroke
				(width 0.1)
				(type default)
			)
			(layer "F.Fab")
		)
		(fp_line
			(start -0.12065 0.3048)
			(end -0.67945 0.3048)
			(stroke
				(width 0.1)
				(type default)
			)
			(layer "F.Fab")
		)
		(fp_line
			(start -0.12065 0.2794)
			(end -0.12065 0.3048)
			(stroke
				(width 0.1)
				(type default)
			)
			(layer "F.Fab")
		)
		(fp_line
			(start -0.12065 -0.2794)
			(end 0.12065 -0.2794)
			(stroke
				(width 0.1)
				(type default)
			)
			(layer "F.Fab")
		)
		(fp_line
			(start -0.12065 -0.305054)
			(end -0.12065 -0.2794)
			(stroke
				(width 0.1)
				(type default)
			)
			(layer "F.Fab")
		)
		(fp_line
			(start -0.67945 0.3048)
			(end -0.67945 -0.305054)
			(stroke
				(width 0.1)
				(type default)
			)
			(layer "F.Fab")
		)
		(fp_line
			(start -0.67945 -0.305054)
			(end -0.12065 -0.305054)
			(stroke
				(width 0.1)
				(type default)
			)
			(layer "F.Fab")
		)
		(pad "1" smd circle
			(at -0.40005 0 180)
			(size 0 0)
			(layers "F.Cu" "F.Mask" "F.Paste")
			(net "GPU_NVS_PWR_BRAKE_N_R")
		)
		(pad "2" smd circle
			(at 0.40005 0 180)
			(size 0 0)
			(layers "F.Cu" "F.Mask" "F.Paste")
			(net "GND")
		)
	)
)
